# T6G (Grand Teton) — schematic netlist excerpt (pin names and nets, part order shuffled) for the footprints in the layout excerpt that follows; sources: Cadence DE-HDL packaged netlist, KiCad conversion of 04192023_DAF0TMB3IC0_F0TG_MB_C_brd_V02_OCP.brd

C2044  Q_CAP  100PF 50V 5% EMPTY  pkg 0402  page 257 : A = P5V_ADC_MAM ; B = GND
R3532  Q_RES  4.7K 5% CHIP  pkg 0402LF  page 148 : A = P3V3_E1S_0 ; B = SMB_E1S_3V3AUX_ISO_SDA_R

(kicad_pcb
	(version 20260206)
	(generator "pcbnew")
	(generator_version "10.0")
	(general
		(thickness 1.6)
		(legacy_teardrops no)
	)
	(paper "A4")
	(title_block
		(title "04192023_DAF0TMB3IC0_F0TG_MB_C_brd_V02_OCP.brd")
		(comment 1 "Grand Teton / footprints 3849-3850 of 8354")
	)
	(layers
		(0 "F.Cu" signal "TOP")
		(4 "In1.Cu" signal "GND")
		(6 "In2.Cu" signal "IN1")
		(8 "In3.Cu" signal "GND1")
		(10 "In4.Cu" signal "IN2")
		(12 "In5.Cu" signal "GND2")
		(14 "In6.Cu" signal "IN3")
		(16 "In7.Cu" signal "GND3")
		(18 "In8.Cu" signal "VCC")
		(20 "In9.Cu" signal "VCC1")
		(22 "In10.Cu" signal "GND4")
		(24 "In11.Cu" signal "IN4")
		(26 "In12.Cu" signal "GND5")
		(28 "In13.Cu" signal "IN5")
		(30 "In14.Cu" signal "GND6")
		(32 "In15.Cu" signal "IN6")
		(34 "In16.Cu" signal "GND7")
		(2 "B.Cu" signal "BOTTOM")
		(9 "F.Adhes" user "F.Adhesive")
		(11 "B.Adhes" user "B.Adhesive")
		(13 "F.Paste" user "Package Geometry/Pastemask Top")
		(15 "B.Paste" user "Package Geometry/Pastemask Bottom")
		(5 "F.SilkS" user "Ref Des/Silkscreen Top")
		(7 "B.SilkS" user "Ref Des/Silkscreen Bottom")
		(1 "F.Mask" user "Board Geometry/Soldermask Top")
		(3 "B.Mask" user "Board Geometry/Soldermask Bottom")
		(17 "Dwgs.User" user "User.Drawings")
		(19 "Cmts.User" user "User.Comments")
		(21 "Eco1.User" user "User.Eco1")
		(23 "Eco2.User" user "User.Eco2")
		(25 "Edge.Cuts" user "Board Geometry/Outline")
		(27 "Margin" user)
		(31 "F.CrtYd" user "Package Geometry/Place Bound Top")
		(29 "B.CrtYd" user "Package Geometry/Place Bound Bottom")
		(35 "F.Fab" user "Ref Des/Assembly Top")
		(33 "B.Fab" user "Ref Des/Assembly Bottom")
	)
	(footprint ""
		(layer "F.Cu")
		(at 221.67088 -44.922948 180)
		(property "Reference" "R3532"
			(at 0 0 180)
			(layer "F.SilkS")
			(hide yes)
			(effects
				(font
					(size 1.27 1.27)
				)
			)
		)
		(property "Value" ""
			(at 0 0 180)
			(layer "F.Fab")
			(effects
				(font
					(size 1.27 1.27)
				)
			)
		)
		(duplicate_pad_numbers_are_jumpers no)
		(fp_line
			(start 0.7874 0.4064)
			(end -0.7874 0.4064)
			(stroke
				(width 0.1524)
				(type default)
			)
			(layer "F.SilkS")
		)
		(fp_line
			(start 0.7874 -0.4064)
			(end 0.7874 0.4064)
			(stroke
				(width 0.1524)
				(type default)
			)
			(layer "F.SilkS")
		)
		(fp_line
			(start -0.7874 0.4064)
			(end -0.7874 -0.4064)
			(stroke
				(width 0.1524)
				(type default)
			)
			(layer "F.SilkS")
		)
		(fp_line
			(start -0.7874 -0.4064)
			(end 0.7874 -0.4064)
			(stroke
				(width 0.1524)
				(type default)
			)
			(layer "F.SilkS")
		)
		(fp_line
			(start 0.67945 0.3048)
			(end 0.120396 0.3048)
			(stroke
				(width 0.1)
				(type default)
			)
			(layer "F.Fab")
		)
		(fp_line
			(start 0.67945 -0.3048)
			(end 0.67945 0.3048)
			(stroke
				(width 0.1)
				(type default)
			)
			(layer "F.Fab")
		)
		(fp_line
			(start 0.12065 -0.2794)
			(end 0.12065 -0.3048)
			(stroke
				(width 0.1)
				(type default)
			)
			(layer "F.Fab")
		)
		(fp_line
			(start 0.12065 -0.3048)
			(end 0.67945 -0.3048)
			(stroke
				(width 0.1)
				(type default)
			)
			(layer "F.Fab")
		)
		(fp_line
			(start 0.120396 0.3048)
			(end 0.120396 0.2794)
			(stroke
				(width 0.1)
				(type default)
			)
			(layer "F.Fab")
		)
		(fp_line
			(start 0.120396 0.2794)
			(end -0.12065 0.2794)
			(stroke
				(width 0.1)
				(type default)
			)
			(layer "F.Fab")
		)
		(fp_line
			(start -0.12065 0.3048)
			(end -0.67945 0.3048)
			(stroke
				(width 0.1)
				(type default)
			)
			(layer "F.Fab")
		)
		(fp_line
			(start -0.12065 0.2794)
			(end -0.12065 0.3048)
			(stroke
				(width 0.1)
				(type default)
			)
			(layer "F.Fab")
		)
		(fp_line
			(start -0.12065 -0.2794)
			(end 0.12065 -0.2794)
			(stroke
				(width 0.1)
				(type default)
			)
			(layer "F.Fab")
		)
		(fp_line
			(start -0.12065 -0.305054)
			(end -0.12065 -0.2794)
			(stroke
				(width 0.1)
				(type default)
			)
			(layer "F.Fab")
		)
		(fp_line
			(start -0.67945 0.3048)
			(end -0.67945 -0.305054)
			(stroke
				(width 0.1)
				(type default)
			)
			(layer "F.Fab")
		)
		(fp_line
			(start -0.67945 -0.305054)
			(end -0.12065 -0.305054)
			(stroke
				(width 0.1)
				(type default)
			)
			(layer "F.Fab")
		)
		(pad "1" smd circle
			(at -0.40005 0 180)
			(size 0 0)
			(layers "F.Cu" "F.Mask" "F.Paste")
			(net "P3V3_E1S_0")
		)
		(pad "2" smd circle
			(at 0.40005 0 180)
			(size 0 0)
			(layers "F.Cu" "F.Mask" "F.Paste")
			(net "SMB_E1S_3V3AUX_ISO_SDA_R")
		)
	)
	(footprint ""
		(layer "F.Cu")
		(at 315.771022 -31.429706 180)
		(property "Reference" "C2044"
			(at 0 0 180)
			(layer "F.SilkS")
			(hide yes)
			(effects
				(font
					(size 1.27 1.27)
				)
			)
		)
		(property "Value" ""
			(at 0 0 180)
			(layer "F.Fab")
			(effects
				(font
					(size 1.27 1.27)
				)
			)
		)
		(duplicate_pad_numbers_are_jumpers no)
		(fp_line
			(start 0.7874 0.4064)
			(end -0.7874 0.4064)
			(stroke
				(width 0.1524)
				(type default)
			)
			(layer "F.SilkS")
		)
		(fp_line
			(start 0.7874 -0.4064)
			(end 0.7874 0.4064)
			(stroke
				(width 0.1524)
				(type default)
			)
			(layer "F.SilkS")
		)
		(fp_line
			(start -0.7874 0.4064)
			(end -0.7874 -0.4064)
			(stroke
				(width 0.1524)
				(type default)
			)
			(layer "F.SilkS")
		)
		(fp_line
			(start -0.7874 -0.4064)
			(end 0.7874 -0.4064)
			(stroke
				(width 0.1524)
				(type default)
			)
			(layer "F.SilkS")
		)
		(fp_line
			(start 0.67945 0.3048)
			(end 0.120396 0.3048)
			(stroke
				(width 0.1)
				(type default)
			)
			(layer "F.Fab")
		)
		(fp_line
			(start 0.67945 -0.3048)
			(end 0.67945 0.3048)
			(stroke
				(width 0.1)
				(type default)
			)
			(layer "F.Fab")
		)
		(fp_line
			(start 0.12065 -0.2794)
			(end 0.12065 -0.3048)
			(stroke
				(width 0.1)
				(type default)
			)
			(layer "F.Fab")
		)
		(fp_line
			(start 0.12065 -0.3048)
			(end 0.67945 -0.3048)
			(stroke
				(width 0.1)
				(type default)
			)
			(layer "F.Fab")
		)
		(fp_line
			(start 0.120396 0.3048)
			(end 0.120396 0.2794)
			(stroke
				(width 0.1)
				(type default)
			)
			(layer "F.Fab")
		)
		(fp_line
			(start 0.120396 0.2794)
			(end -0.12065 0.2794)
			(stroke
				(width 0.1)
				(type default)
			)
			(layer "F.Fab")
		)
		(fp_line
			(start -0.12065 0.3048)
			(end -0.67945 0.3048)
			(stroke
				(width 0.1)
				(type default)
			)
			(layer "F.Fab")
		)
		(fp_line
			(start -0.12065 0.2794)
			(end -0.12065 0.3048)
			(stroke
				(width 0.1)
				(type default)
			)
			(layer "F.Fab")
		)
		(fp_line
			(start -0.12065 -0.2794)
			(end 0.12065 -0.2794)
			(stroke
				(width 0.1)
				(type default)
			)
			(layer "F.Fab")
		)
		(fp_line
			(start -0.12065 -0.305054)
			(end -0.12065 -0.2794)
			(stroke
				(width 0.1)
				(type default)
			)
			(layer "F.Fab")
		)
		(fp_line
			(start -0.67945 0.3048)
			(end -0.67945 -0.305054)
			(stroke
				(width 0.1)
				(type default)
			)
			(layer "F.Fab")
		)
		(fp_line
			(start -0.67945 -0.305054)
			(end -0.12065 -0.305054)
			(stroke
				(width 0.1)
				(type default)
			)
			(layer "F.Fab")
		)
		(pad "1" smd circle
			(at -0.40005 0 180)
			(size 0 0)
			(layers "F.Cu" "F.Mask" "F.Paste")
			(net "P5V_ADC_MAM")
		)
		(pad "2" smd circle
			(at 0.40005 0 180)
			(size 0 0)
			(layers "F.Cu" "F.Mask" "F.Paste")
			(net "GND")
		)
	)
)
